(kicad_pcb
	(version 20241229)
	(generator "pcbnew")
	(generator_version "9.0")
	(general
		(thickness 1.292)
		(legacy_teardrops no)
	)
	(paper "A4")
	(title_block
		(title "LPDDR5 Testbed")
		(date "2023-12-19")
		(rev "1.0.0")
		(comment 9 "footprints 69-74 of 160")
	)
	(layers
		(0 "F.Cu" signal)
		(4 "In1.Cu" power)
		(6 "In2.Cu" power)
		(8 "In3.Cu" signal)
		(10 "In4.Cu" signal)
		(2 "B.Cu" signal)
		(9 "F.Adhes" user "F.Adhesive")
		(11 "B.Adhes" user "B.Adhesive")
		(13 "F.Paste" user)
		(15 "B.Paste" user)
		(5 "F.SilkS" user "F.Silkscreen")
		(7 "B.SilkS" user "B.Silkscreen")
		(1 "F.Mask" user)
		(3 "B.Mask" user)
		(17 "Dwgs.User" user "User.Drawings")
		(19 "Cmts.User" user "User.Comments")
		(21 "Eco1.User" user "User.Eco1")
		(23 "Eco2.User" user "User.Eco2")
		(25 "Edge.Cuts" user)
		(27 "Margin" user)
		(31 "F.CrtYd" user "F.Courtyard")
		(29 "B.CrtYd" user "B.Courtyard")
		(35 "F.Fab" user)
		(33 "B.Fab" user)
	)
	(footprint "antmicro-footprints:R_Array_4x0402_Panasonic_EXB28V"
		(layer "F.Cu")
		(at 108.85 93.8)
		(property "Reference" "R10"
			(at -1.301 -1.45 0)
			(unlocked yes)
			(layer "F.SilkS")
			(effects
				(font
					(size 0.7 0.7)
					(thickness 0.15)
				)
				(justify left bottom)
			)
		)
		(property "Value" "R_4x100R_0402_array"
			(at -1.5 2 0)
			(layer "F.Fab")
			(effects
				(font
					(size 0.7 0.7)
					(thickness 0.15)
				)
				(justify left bottom)
			)
		)
		(property "Author" "Antmicro"
			(at 0 0 0)
			(layer "F.Fab")
			(hide yes)
			(effects
				(font
					(size 1 1)
					(thickness 0.15)
				)
			)
		)
		(property "License" "Apache-2.0"
			(at 0 0 0)
			(layer "F.Fab")
			(hide yes)
			(effects
				(font
					(size 1 1)
					(thickness 0.15)
				)
			)
		)
		(property "MPN" "EXB-28V101JX"
			(at 0 0 0)
			(layer "F.Fab")
			(hide yes)
			(effects
				(font
					(size 1 1)
					(thickness 0.15)
				)
			)
		)
		(property "Manufacturer" "Panasonic"
			(at 0 0 0)
			(layer "F.Fab")
			(hide yes)
			(effects
				(font
					(size 1 1)
					(thickness 0.15)
				)
			)
		)
		(property "Val" "R_4x100R_0402"
			(at 0 0 0)
			(layer "F.Fab")
			(hide yes)
			(effects
				(font
					(size 1 1)
					(thickness 0.15)
				)
			)
		)
		(sheetname "Translators")
		(sheetfile "translators.kicad_sch")
		(attr smd)
		(fp_line
			(start -1.25 -0.5)
			(end -1.25 0.498)
			(stroke
				(width 0.15)
				(type solid)
			)
			(layer "F.SilkS")
		)
		(fp_line
			(start 1.25 0.499)
			(end 1.25 -0.499)
			(stroke
				(width 0.15)
				(type solid)
			)
			(layer "F.SilkS")
		)
		(fp_rect
			(start -1.25 -0.8)
			(end 1.25 0.8)
			(stroke
				(width 0.05)
				(type solid)
			)
			(fill no)
			(layer "F.CrtYd")
		)
		(fp_line
			(start -1 -0.5)
			(end 0.998 -0.5)
			(stroke
				(width 0.15)
				(type solid)
			)
			(layer "F.Fab")
		)
		(fp_line
			(start -1 0.498)
			(end -1 -0.5)
			(stroke
				(width 0.15)
				(type solid)
			)
			(layer "F.Fab")
		)
		(fp_line
			(start 0.998 -0.5)
			(end 0.998 0.498)
			(stroke
				(width 0.15)
				(type solid)
			)
			(layer "F.Fab")
		)
		(fp_line
			(start 0.998 0.498)
			(end -1 0.498)
			(stroke
				(width 0.15)
				(type solid)
			)
			(layer "F.Fab")
		)
		(pad "1" smd roundrect
			(at -0.8875 0.45)
			(size 0.525 0.5)
			(layers "F.Cu" "F.Mask" "F.Paste")
			(roundrect_rratio 0.25)
			(net 177 "/SODIMM/LPDDR5_IN_A.DQ15")
			(pinfunction "R1.1")
			(pintype "passive")
		)
		(pad "2" smd roundrect
			(at -0.25 0.45)
			(size 0.25 0.5)
			(layers "F.Cu" "F.Mask" "F.Paste")
			(roundrect_rratio 0.25)
			(net 180 "/SODIMM/LPDDR5_IN_A.DQ14")
			(pinfunction "R2.1")
			(pintype "passive")
		)
		(pad "3" smd roundrect
			(at 0.25 0.45)
			(size 0.25 0.5)
			(layers "F.Cu" "F.Mask" "F.Paste")
			(roundrect_rratio 0.25)
			(net 178 "/SODIMM/LPDDR5_IN_A.DQ12")
			(pinfunction "R3.1")
			(pintype "passive")
		)
		(pad "4" smd roundrect
			(at 0.8875 0.45)
			(size 0.525 0.5)
			(layers "F.Cu" "F.Mask" "F.Paste")
			(roundrect_rratio 0.25)
			(net 179 "/SODIMM/LPDDR5_IN_A.DQ13")
			(pinfunction "R4.1")
			(pintype "passive")
		)
		(pad "5" smd roundrect
			(at 0.8875 -0.45)
			(size 0.525 0.5)
			(layers "F.Cu" "F.Mask" "F.Paste")
			(roundrect_rratio 0.25)
			(net 194 "/LPDDR5/LPDDR5_A.DQ13")
			(pinfunction "R4.2")
			(pintype "passive")
		)
		(pad "6" smd roundrect
			(at 0.25 -0.45)
			(size 0.25 0.5)
			(layers "F.Cu" "F.Mask" "F.Paste")
			(roundrect_rratio 0.25)
			(net 193 "/LPDDR5/LPDDR5_A.DQ12")
			(pinfunction "R3.2")
			(pintype "passive")
		)
		(pad "7" smd roundrect
			(at -0.25 -0.45)
			(size 0.25 0.5)
			(layers "F.Cu" "F.Mask" "F.Paste")
			(roundrect_rratio 0.25)
			(net 192 "/LPDDR5/LPDDR5_A.DQ14")
			(pinfunction "R2.2")
			(pintype "passive")
		)
		(pad "8" smd roundrect
			(at -0.8875 -0.45)
			(size 0.525 0.5)
			(layers "F.Cu" "F.Mask" "F.Paste")
			(roundrect_rratio 0.25)
			(net 191 "/LPDDR5/LPDDR5_A.DQ15")
			(pinfunction "R1.2")
			(pintype "passive")
		)
	)
	(footprint "antmicro-footprints:TP_SMD_0.75mm"
		(layer "F.Cu")
		(at 112.1 71.7)
		(property "Reference" "TP6"
			(at 2.5 2.5 0)
			(unlocked yes)
			(layer "F.SilkS")
			(effects
				(font
					(size 0.7 0.7)
					(thickness 0.15)
				)
				(justify left bottom)
			)
		)
		(property "Value" "TP_0.75mm_SMD"
			(at 0 1.2 0)
			(layer "F.Fab")
			(effects
				(font
					(size 0.7 0.7)
					(thickness 0.15)
				)
				(justify left bottom)
			)
		)
		(property "Author" "Antmicro"
			(at 0 0 0)
			(layer "F.Fab")
			(hide yes)
			(effects
				(font
					(size 1 1)
					(thickness 0.15)
				)
			)
		)
		(property "License" "Apache-2.0"
			(at 0 0 0)
			(layer "F.Fab")
			(hide yes)
			(effects
				(font
					(size 1 1)
					(thickness 0.15)
				)
			)
		)
		(property "MPN" ""
			(at 0 0 0)
			(layer "F.Fab")
			(hide yes)
			(effects
				(font
					(size 1 1)
					(thickness 0.15)
				)
			)
		)
		(property "Manufacturer" ""
			(at 0 0 0)
			(layer "F.Fab")
			(hide yes)
			(effects
				(font
					(size 1 1)
					(thickness 0.15)
				)
			)
		)
		(sheetname "Power supply")
		(sheetfile "power_supply.kicad_sch")
		(attr exclude_from_pos_files)
		(pad "1" smd circle
			(at 0 0)
			(size 0.75 0.75)
			(layers "F.Cu" "F.Mask")
			(net 9 "/Power supply/VOUT3")
			(pinfunction "1")
			(pintype "passive")
		)
	)
	(footprint "antmicro-footprints:C_0603_1608Metric"
		(layer "F.Cu")
		(at 101.4875 69.725 -90)
		(descr "Capacitor SMD 0603")
		(tags "capacitor 0603")
		(property "Reference" "C19"
			(at -1.325 -0.8125 0)
			(unlocked yes)
			(layer "F.SilkS")
			(effects
				(font
					(size 0.7 0.7)
					(thickness 0.15)
				)
				(justify right bottom)
			)
		)
		(property "Value" "C_22u_0603"
			(at -1.42757 1.770288 90)
			(layer "F.Fab")
			(effects
				(font
					(size 0.7 0.7)
					(thickness 0.15)
				)
				(justify right bottom)
			)
		)
		(property "Author" "Antmicro"
			(at 31.7625 171.2125 0)
			(layer "F.Fab")
			(hide yes)
			(effects
				(font
					(size 1 1)
					(thickness 0.15)
				)
			)
		)
		(property "Dielectric" ""
			(at 31.7625 171.2125 0)
			(layer "F.Fab")
			(hide yes)
			(effects
				(font
					(size 1 1)
					(thickness 0.15)
				)
			)
		)
		(property "License" "Apache-2.0"
			(at 31.7625 171.2125 0)
			(layer "F.Fab")
			(hide yes)
			(effects
				(font
					(size 1 1)
					(thickness 0.15)
				)
			)
		)
		(property "MPN" "GRM188R60J226MEA0D"
			(at 31.7625 171.2125 0)
			(layer "F.Fab")
			(hide yes)
			(effects
				(font
					(size 1 1)
					(thickness 0.15)
				)
			)
		)
		(property "Manufacturer" "Murata"
			(at 31.7625 171.2125 0)
			(layer "F.Fab")
			(hide yes)
			(effects
				(font
					(size 1 1)
					(thickness 0.15)
				)
			)
		)
		(property "Val" "22u"
			(at 31.7625 171.2125 0)
			(layer "F.Fab")
			(hide yes)
			(effects
				(font
					(size 1 1)
					(thickness 0.15)
				)
			)
		)
		(property "Voltage" ""
			(at 31.7625 171.2125 0)
			(layer "F.Fab")
			(hide yes)
			(effects
				(font
					(size 1 1)
					(thickness 0.15)
				)
			)
		)
		(sheetname "Power supply")
		(sheetfile "power_supply.kicad_sch")
		(attr smd)
		(fp_line
			(start -0.3 0.3)
			(end 0.3 0.3)
			(stroke
				(width 0.15)
				(type solid)
			)
			(layer "F.SilkS")
		)
		(fp_line
			(start -0.3 -0.3)
			(end 0.3 -0.3)
			(stroke
				(width 0.15)
				(type solid)
			)
			(layer "F.SilkS")
		)
		(fp_rect
			(start -1.24 -0.7)
			(end 1.24 0.7)
			(stroke
				(width 0.05)
				(type solid)
			)
			(fill no)
			(layer "F.CrtYd")
		)
		(fp_rect
			(start -0.8 -0.4)
			(end 0.8 0.4)
			(stroke
				(width 0.15)
				(type solid)
			)
			(fill no)
			(layer "F.Fab")
		)
		(pad "1" smd roundrect
			(at -0.7 0 270)
			(size 0.6 0.8)
			(layers "F.Cu" "F.Mask" "F.Paste")
			(roundrect_rratio 0.2)
			(net 14 "GND")
			(pintype "passive")
		)
		(pad "2" smd roundrect
			(at 0.7 0 270)
			(size 0.6 0.8)
			(layers "F.Cu" "F.Mask" "F.Paste")
			(roundrect_rratio 0.2)
			(net 10 "/Power supply/VOUT4")
			(pintype "passive")
		)
	)
	(footprint "antmicro-footprints:R_0402_1005Metric"
		(layer "F.Cu")
		(at 167.125 69 90)
		(descr "Resistor SMD 0402")
		(tags "resistor SMD 0402")
		(property "Reference" "R32"
			(at -9.7 0.275 90)
			(unlocked yes)
			(layer "F.SilkS")
			(effects
				(font
					(size 0.7 0.7)
					(thickness 0.15)
				)
				(justify left bottom)
			)
		)
		(property "Value" "R_25k5_0402"
			(at -1.011843 1.772047 90)
			(layer "F.Fab")
			(effects
				(font
					(size 0.7 0.7)
					(thickness 0.15)
				)
				(justify left bottom)
			)
		)
		(property "Author" "Antmicro"
			(at 236.125 -98.125 0)
			(layer "F.Fab")
			(hide yes)
			(effects
				(font
					(size 1 1)
					(thickness 0.15)
				)
			)
		)
		(property "License" "Apache-2.0"
			(at 236.125 -98.125 0)
			(layer "F.Fab")
			(hide yes)
			(effects
				(font
					(size 1 1)
					(thickness 0.15)
				)
			)
		)
		(property "MPN" "CR0402-FX-2552GLF"
			(at 236.125 -98.125 0)
			(layer "F.Fab")
			(hide yes)
			(effects
				(font
					(size 1 1)
					(thickness 0.15)
				)
			)
		)
		(property "Manufacturer" "Bourns"
			(at 236.125 -98.125 0)
			(layer "F.Fab")
			(hide yes)
			(effects
				(font
					(size 1 1)
					(thickness 0.15)
				)
			)
		)
		(property "Tolerance" "1%"
			(at 236.125 -98.125 0)
			(layer "F.Fab")
			(hide yes)
			(effects
				(font
					(size 1 1)
					(thickness 0.15)
				)
			)
		)
		(property "Val" "25k5"
			(at 236.125 -98.125 0)
			(layer "F.Fab")
			(hide yes)
			(effects
				(font
					(size 1 1)
					(thickness 0.15)
				)
			)
		)
		(sheetname "Power supply")
		(sheetfile "power_supply.kicad_sch")
		(attr smd)
		(fp_rect
			(start -0.93 -0.47)
			(end 0.93 0.47)
			(stroke
				(width 0.05)
				(type solid)
			)
			(fill no)
			(layer "F.CrtYd")
		)
		(fp_rect
			(start -0.5 -0.25)
			(end 0.5 0.25)
			(stroke
				(width 0.15)
				(type solid)
			)
			(fill no)
			(layer "F.Fab")
		)
		(pad "1" smd roundrect
			(at -0.485 0 90)
			(size 0.59 0.64)
			(layers "F.Cu" "F.Mask" "F.Paste")
			(roundrect_rratio 0.25)
			(net 14 "GND")
			(pintype "passive")
		)
		(pad "2" smd roundrect
			(at 0.485 0 90)
			(size 0.59 0.64)
			(layers "F.Cu" "F.Mask" "F.Paste")
			(roundrect_rratio 0.25)
			(net 69 "Net-(R32-Pad2)")
			(pintype "passive")
		)
	)
	(footprint "antmicro-footprints:R_0402_1005Metric"
		(layer "F.Cu")
		(at 131.675 72.275 180)
		(descr "Resistor SMD 0402")
		(tags "resistor SMD 0402")
		(property "Reference" "R69"
			(at 0.99 -0.475 0)
			(unlocked yes)
			(layer "F.SilkS")
			(effects
				(font
					(size 0.7 0.7)
					(thickness 0.15)
				)
				(justify right bottom)
			)
		)
		(property "Value" "R_240R_0402"
			(at -1.011843 1.772047 0)
			(layer "F.Fab")
			(effects
				(font
					(size 0.7 0.7)
					(thickness 0.15)
				)
				(justify right bottom)
			)
		)
		(property "Author" "Antmicro"
			(at 263.35 144.55 0)
			(layer "F.Fab")
			(hide yes)
			(effects
				(font
					(size 1 1)
					(thickness 0.15)
				)
			)
		)
		(property "License" "Apache-2.0"
			(at 263.35 144.55 0)
			(layer "F.Fab")
			(hide yes)
			(effects
				(font
					(size 1 1)
					(thickness 0.15)
				)
			)
		)
		(property "MPN" "CR0402-FX-2400GLF"
			(at 263.35 144.55 0)
			(layer "F.Fab")
			(hide yes)
			(effects
				(font
					(size 1 1)
					(thickness 0.15)
				)
			)
		)
		(property "Manufacturer" "Bourns"
			(at 263.35 144.55 0)
			(layer "F.Fab")
			(hide yes)
			(effects
				(font
					(size 1 1)
					(thickness 0.15)
				)
			)
		)
		(property "Tolerance" "1%"
			(at 263.35 144.55 0)
			(layer "F.Fab")
			(hide yes)
			(effects
				(font
					(size 1 1)
					(thickness 0.15)
				)
			)
		)
		(property "Val" "240R"
			(at 263.35 144.55 0)
			(layer "F.Fab")
			(hide yes)
			(effects
				(font
					(size 1 1)
					(thickness 0.15)
				)
			)
		)
		(sheetname "LPDDR5")
		(sheetfile "lpddr5.kicad_sch")
		(attr smd)
		(fp_rect
			(start -0.93 -0.47)
			(end 0.93 0.47)
			(stroke
				(width 0.05)
				(type solid)
			)
			(fill no)
			(layer "F.CrtYd")
		)
		(fp_rect
			(start -0.5 -0.25)
			(end 0.5 0.25)
			(stroke
				(width 0.15)
				(type solid)
			)
			(fill no)
			(layer "F.Fab")
		)
		(pad "1" smd roundrect
			(at -0.485 0 180)
			(size 0.59 0.64)
			(layers "F.Cu" "F.Mask" "F.Paste")
			(roundrect_rratio 0.25)
			(net 14 "GND")
			(pintype "passive")
		)
		(pad "2" smd roundrect
			(at 0.485 0 180)
			(size 0.59 0.64)
			(layers "F.Cu" "F.Mask" "F.Paste")
			(roundrect_rratio 0.25)
			(net 92 "Net-(R69-Pad2)")
			(pintype "passive")
		)
	)
	(footprint "antmicro-footprints:R_Array_4x0402_Panasonic_EXB28V"
		(layer "F.Cu")
		(at 144.2 93.8 180)
		(property "Reference" "R75"
			(at -1 1.4 0)
			(unlocked yes)
			(layer "F.SilkS")
			(effects
				(font
					(size 0.7 0.7)
					(thickness 0.15)
				)
				(justify right bottom)
			)
		)
		(property "Value" "R_4x100R_0402_array"
			(at -1.5 2 0)
			(layer "F.Fab")
			(effects
				(font
					(size 0.7 0.7)
					(thickness 0.15)
				)
				(justify right bottom)
			)
		)
		(property "Author" "Antmicro"
			(at 288.4 187.6 0)
			(layer "F.Fab")
			(hide yes)
			(effects
				(font
					(size 1 1)
					(thickness 0.15)
				)
			)
		)
		(property "License" "Apache-2.0"
			(at 288.4 187.6 0)
			(layer "F.Fab")
			(hide yes)
			(effects
				(font
					(size 1 1)
					(thickness 0.15)
				)
			)
		)
		(property "MPN" "EXB-28V101JX"
			(at 288.4 187.6 0)
			(layer "F.Fab")
			(hide yes)
			(effects
				(font
					(size 1 1)
					(thickness 0.15)
				)
			)
		)
		(property "Manufacturer" "Panasonic"
			(at 288.4 187.6 0)
			(layer "F.Fab")
			(hide yes)
			(effects
				(font
					(size 1 1)
					(thickness 0.15)
				)
			)
		)
		(property "Val" "R_4x100R_0402"
			(at 288.4 187.6 0)
			(layer "F.Fab")
			(hide yes)
			(effects
				(font
					(size 1 1)
					(thickness 0.15)
				)
			)
		)
		(sheetname "Translators1")
		(sheetfile "translators.kicad_sch")
		(attr smd)
		(fp_line
			(start 1.25 0.499)
			(end 1.25 -0.499)
			(stroke
				(width 0.15)
				(type solid)
			)
			(layer "F.SilkS")
		)
		(fp_line
			(start -1.25 -0.5)
			(end -1.25 0.498)
			(stroke
				(width 0.15)
				(type solid)
			)
			(layer "F.SilkS")
		)
		(fp_rect
			(start -1.25 -0.8)
			(end 1.25 0.8)
			(stroke
				(width 0.05)
				(type solid)
			)
			(fill no)
			(layer "F.CrtYd")
		)
		(fp_line
			(start 0.998 0.498)
			(end -1 0.498)
			(stroke
				(width 0.15)
				(type solid)
			)
			(layer "F.Fab")
		)
		(fp_line
			(start 0.998 -0.5)
			(end 0.998 0.498)
			(stroke
				(width 0.15)
				(type solid)
			)
			(layer "F.Fab")
		)
		(fp_line
			(start -1 0.498)
			(end -1 -0.5)
			(stroke
				(width 0.15)
				(type solid)
			)
			(layer "F.Fab")
		)
		(fp_line
			(start -1 -0.5)
			(end 0.998 -0.5)
			(stroke
				(width 0.15)
				(type solid)
			)
			(layer "F.Fab")
		)
		(pad "1" smd roundrect
			(at -0.8875 0.45 180)
			(size 0.525 0.5)
			(layers "F.Cu" "F.Mask" "F.Paste")
			(roundrect_rratio 0.25)
			(net 106 "/LPDDR5/LPDDR5_B.CS0")
			(pinfunction "R1.1")
			(pintype "passive")
		)
		(pad "2" smd roundrect
			(at -0.25 0.45 180)
			(size 0.25 0.5)
			(layers "F.Cu" "F.Mask" "F.Paste")
			(roundrect_rratio 0.25)
			(net 107 "/LPDDR5/LPDDR5_B.CS1")
			(pinfunction "R2.1")
			(pintype "passive")
		)
		(pad "3" smd roundrect
			(at 0.25 0.45 180)
			(size 0.25 0.5)
			(layers "F.Cu" "F.Mask" "F.Paste")
			(roundrect_rratio 0.25)
			(net 102 "/LPDDR5/LPDDR5_B.CA0")
			(pinfunction "R3.1")
			(pintype "passive")
		)
		(pad "4" smd roundrect
			(at 0.8875 0.45 180)
			(size 0.525 0.5)
			(layers "F.Cu" "F.Mask" "F.Paste")
			(roundrect_rratio 0.25)
			(net 103 "/LPDDR5/LPDDR5_B.CA1")
			(pinfunction "R4.1")
			(pintype "passive")
		)
		(pad "5" smd roundrect
			(at 0.8875 -0.45 180)
			(size 0.525 0.5)
			(layers "F.Cu" "F.Mask" "F.Paste")
			(roundrect_rratio 0.25)
			(net 14 "GND")
			(pinfunction "R4.2")
			(pintype "passive")
		)
		(pad "6" smd roundrect
			(at 0.25 -0.45 180)
			(size 0.25 0.5)
			(layers "F.Cu" "F.Mask" "F.Paste")
			(roundrect_rratio 0.25)
			(net 14 "GND")
			(pinfunction "R3.2")
			(pintype "passive")
		)
		(pad "7" smd roundrect
			(at -0.25 -0.45 180)
			(size 0.25 0.5)
			(layers "F.Cu" "F.Mask" "F.Paste")
			(roundrect_rratio 0.25)
			(net 14 "GND")
			(pinfunction "R2.2")
			(pintype "passive")
		)
		(pad "8" smd roundrect
			(at -0.8875 -0.45 180)
			(size 0.525 0.5)
			(layers "F.Cu" "F.Mask" "F.Paste")
			(roundrect_rratio 0.25)
			(net 14 "GND")
			(pinfunction "R1.2")
			(pintype "passive")
		)
	)
)
